# T6G (Grand Teton) — schematic parts with pin connectivity, parts 2602–2602 of 8303; source: Cadence DE-HDL packaged netlist (pstxprt.dat, pstxnet.dat, pstchip.dat)

J20  SCONN288_DDR506112002KQ  IO  pkg DDR288S_1-1VXC  page 96
  1  VIN_BULK0  POWER  = P12V_MEM_CPU0
  2  RFU0  TRI  = NC
  3  VIN_MGMT  POWER  = P3V3_AUX
  4  HSCL  IN  = I3C_SPD_DDRK_CPU0_SCL
  5  HSDA  BI  = I3C_SPD_DDRK_CPU0_SDA
  6  VSS0  POWER  = GND
  7  DQ0_A  BI  = M_K_CPU0_SA_DQ<0>
  8  VSS1  POWER  = GND
  9  DQ1_A  BI  = M_K_CPU0_SA_DQ<1>
  10  VSS2  POWER  = GND
  11  DQS0_A_T  BI  = M_K_CPU0_SA_DQS_DP<0>
  12  DQS0_A_C  BI  = M_K_CPU0_SA_DQS_DN<0>
  13  VSS3  POWER  = GND
  14  DQ4_A  BI  = M_K_CPU0_SA_DQ<4>
  15  VSS4  POWER  = GND
  16  DQ5_A  BI  = M_K_CPU0_SA_DQ<5>
  17  VSS5  POWER  = GND
  18  DQ8_A  BI  = M_K_CPU0_SA_DQ<8>
  19  VSS6  POWER  = GND
  20  DQ9_A  BI  = M_K_CPU0_SA_DQ<9>
  21  VSS7  POWER  = GND
  22  DQS1_A_T  BI  = M_K_CPU0_SA_DQS_DP<1>
  23  DQS1_A_C  BI  = M_K_CPU0_SA_DQS_DN<1>
  24  VSS8  POWER  = GND
  25  DQ12_A  BI  = M_K_CPU0_SA_DQ<12>
  26  VSS9  POWER  = GND
  27  DQ13_A  BI  = M_K_CPU0_SA_DQ<13>
  28  VSS10  POWER  = GND
  29  DQ16_A  BI  = M_K_CPU0_SA_DQ<16>
  30  VSS11  POWER  = GND
  31  DQ17_A  BI  = M_K_CPU0_SA_DQ<17>
  32  VSS12  POWER  = GND
  33  DQS2_A_T  BI  = M_K_CPU0_SA_DQS_DP<2>
  34  DQS2_A_C  BI  = M_K_CPU0_SA_DQS_DN<2>
  35  VSS13  POWER  = GND
  36  DQ20_A  BI  = M_K_CPU0_SA_DQ<20>
  37  VSS14  POWER  = GND
  38  DQ21_A  BI  = M_K_CPU0_SA_DQ<21>
  39  VSS15  POWER  = GND
  40  DQ24_A  BI  = M_K_CPU0_SA_DQ<24>
  41  VSS16  POWER  = GND
  42  DQ25_A  BI  = M_K_CPU0_SA_DQ<25>
  43  VSS17  POWER  = GND
  44  DQS3_A_T  BI  = M_K_CPU0_SA_DQS_DP<3>
  45  DQS3_A_C  BI  = M_K_CPU0_SA_DQS_DN<3>
  46  VSS18  POWER  = GND
  47  DQ28_A  BI  = M_K_CPU0_SA_DQ<28>
  48  VSS19  POWER  = GND
  49  DQ29_A  BI  = M_K_CPU0_SA_DQ<29>
  50  VSS20  POWER  = GND
  51  CB0_A  BI  = M_K_CPU0_SA_CB<0>
  52  VSS21  POWER  = GND
  53  CB1_A  BI  = M_K_CPU0_SA_CB<1>
  54  VSS22  POWER  = GND
  55  DQS4_A_T  BI  = M_K_CPU0_SA_DQS_DP<4>
  56  DQS4_A_C  BI  = M_K_CPU0_SA_DQS_DN<4>
  57  VSS23  POWER  = GND
  58  CB4_A  BI  = M_K_CPU0_SA_CB<4>
  59  VSS24  POWER  = GND
  60  CB5_A  BI  = M_K_CPU0_SA_CB<5>
  61  VSS25  POWER  = GND
  62  ALERT_N  OUT  = M_K_CPU0_ALERT_N
  63  VSS26  POWER  = GND
  64  CS0_A_N  IN  = M_K_CPU0_SA_CS_N<0>
  65  VSS27  POWER  = GND
  66  CA0_A  IN  = M_K_CPU0_SA_CA<0>
  67  VSS28  POWER  = GND
  68  CA2_A  IN  = M_K_CPU0_SA_CA<2>
  69  VSS29  POWER  = GND
  70  CA4_A  IN  = M_K_CPU0_SA_CA<4>
  71  VSS30  POWER  = GND
  72  CA6_A  IN  = M_K_CPU0_SA_CA<6>
  73  VSS31  POWER  = GND
  74  PAR_A  IN  = M_K_CPU0_SA_PAR
  75  VSS32  POWER  = GND
  76  CA0_B  IN  = M_K_CPU0_SB_CA<0>
  77  VSS33  POWER  = GND
  78  CA2_B  IN  = M_K_CPU0_SB_CA<2>
  79  VSS34  POWER  = GND
  80  CA4_B  IN  = M_K_CPU0_SB_CA<4>
  81  VSS35  POWER  = GND
  82  CA6_B  IN  = M_K_CPU0_SB_CA<6>
  83  VSS36  POWER  = GND
  84  CS0_B_N  IN  = M_K_CPU0_SB_CS_N<0>
  85  VSS37  POWER  = GND
  86  \lbd||rsp_a_n\  OUT  = M_K_CPU0_SA_RSP<0>
  87  \lbs||rsp_b_n\  OUT  = M_K_CPU0_SB_RSP<0>
  88  VSS38  POWER  = GND
  89  CB4_B  BI  = M_K_CPU0_SB_CB<4>
  90  VSS39  POWER  = GND
  91  CB5_B  BI  = M_K_CPU0_SB_CB<5>
  92  VSS40  POWER  = GND
  93  \dqs9_b_t||tdqs9_b_t||dbi4_b_n\  BI  = M_K_CPU0_SB_DQS_DP<9>
  94  \dqs9_b_c||tdqs9_b_c\  BI  = M_K_CPU0_SB_DQS_DN<9>
  95  VSS41  POWER  = GND
  96  CB0_B  BI  = M_K_CPU0_SB_CB<0>
  97  VSS42  POWER  = GND
  98  CB1_B  BI  = M_K_CPU0_SB_CB<1>
  99  VSS43  POWER  = GND
  100  DQ0_B  BI  = M_K_CPU0_SB_DQ<0>
  101  VSS44  POWER  = GND
  102  DQ1_B  BI  = M_K_CPU0_SB_DQ<1>
  103  VSS45  POWER  = GND
  104  DQS0_B_T  BI  = M_K_CPU0_SB_DQS_DP<0>
  105  DQS0_B_C  BI  = M_K_CPU0_SB_DQS_DN<0>
  106  VSS46  POWER  = GND
  107  DQ4_B  BI  = M_K_CPU0_SB_DQ<4>
  108  VSS47  POWER  = GND
  109  DQ5_B  BI  = M_K_CPU0_SB_DQ<5>
  110  VSS48  POWER  = GND
  111  DQ8_B  BI  = M_K_CPU0_SB_DQ<8>
  112  VSS49  POWER  = GND
  113  DQ9_B  BI  = M_K_CPU0_SB_DQ<9>
  114  VSS50  POWER  = GND
  115  DQS1_B_T  BI  = M_K_CPU0_SB_DQS_DP<1>
  116  DQS1_B_C  BI  = M_K_CPU0_SB_DQS_DN<1>
  117  VSS51  POWER  = GND
  118  DQ12_B  BI  = M_K_CPU0_SB_DQ<12>
  119  VSS52  POWER  = GND
  120  DQ13_B  BI  = M_K_CPU0_SB_DQ<13>
  121  VSS53  POWER  = GND
  122  DQ16_B  BI  = M_K_CPU0_SB_DQ<16>
  123  VSS54  POWER  = GND
  124  DQ17_B  BI  = M_K_CPU0_SB_DQ<17>
  125  VSS55  POWER  = GND
  126  DQS2_B_T  BI  = M_K_CPU0_SB_DQS_DP<2>
  127  DQS2_B_C  BI  = M_K_CPU0_SB_DQS_DN<2>
  128  VSS56  POWER  = GND
  129  DQ20_B  BI  = M_K_CPU0_SB_DQ<20>
  130  VSS57  POWER  = GND
  131  DQ21_B  BI  = M_K_CPU0_SB_DQ<21>
  132  VSS58  POWER  = GND
  133  DQ24_B  BI  = M_K_CPU0_SB_DQ<24>
  134  VSS59  POWER  = GND
  135  DQ25_B  BI  = M_K_CPU0_SB_DQ<25>
  136  VSS60  POWER  = GND
  137  DQS3_B_T  BI  = M_K_CPU0_SB_DQS_DP<3>
  138  DQS3_B_C  BI  = M_K_CPU0_SB_DQS_DN<3>
  139  VSS61  POWER  = GND
  140  DQ28_B  BI  = M_K_CPU0_SB_DQ<28>
  141  VSS62  POWER  = GND
  142  DQ29_B  BI  = M_K_CPU0_SB_DQ<29>
  143  VSS63  POWER  = GND
  144  RFU1  TRI  = NC
  145  VIN_BULK1  POWER  = P12V_MEM_CPU0
  146  VIN_BULK2  POWER  = P12V_MEM_CPU0
  147  \pwr_good||fail_n\  BI  = PWRGD_CHK_CPU0_DIMM
  148  HAS  IN  = PD_CHK_CPU0_DIMM_SAA
  149  RFU2  TRI  = NC
  150  RFU3  TRI  = NC
  151  VSS64  POWER  = GND
  152  DQ2_A  BI  = M_K_CPU0_SA_DQ<2>
  153  VSS65  POWER  = GND
  154  DQ3_A  BI  = M_K_CPU0_SA_DQ<3>
  155  VSS66  POWER  = GND
  156  \dqs5_a_c||tdqs5_a_c||dqs5_a_t||tdqs5_a_t\  BI  = M_K_CPU0_SA_DQS_DN<5>
  157  \dqs5_a_t||tdqs5_a_t\  BI  = M_K_CPU0_SA_DQS_DP<5>
  158  VSS67  POWER  = GND
  159  DQ6_A  BI  = M_K_CPU0_SA_DQ<6>
  160  VSS68  POWER  = GND
  161  DQ7_A  BI  = M_K_CPU0_SA_DQ<7>
  162  VSS69  POWER  = GND
  163  DQ10_A  BI  = M_K_CPU0_SA_DQ<10>
  164  VSS70  POWER  = GND
  165  DQ11_A  BI  = M_K_CPU0_SA_DQ<11>
  166  VSS71  POWER  = GND
  167  \dqs6_a_c||tdqs6_a_c||dqs6_a_t||tdqs6_a_t\  BI  = M_K_CPU0_SA_DQS_DN<6>
  168  \dqs6_a_t||tdqs6_a_t\  BI  = M_K_CPU0_SA_DQS_DP<6>
  169  VSS72  POWER  = GND
  170  DQ14_A  BI  = M_K_CPU0_SA_DQ<14>
  171  VSS73  POWER  = GND
  172  DQ15_A  BI  = M_K_CPU0_SA_DQ<15>
  173  VSS74  POWER  = GND
  174  DQ18_A  BI  = M_K_CPU0_SA_DQ<18>
  175  VSS75  POWER  = GND
  176  DQ19_A  BI  = M_K_CPU0_SA_DQ<19>
  177  VSS76  POWER  = GND
  178  \dqs7_a_c||tdqs7_a_c\  BI  = M_K_CPU0_SA_DQS_DN<7>
  179  \dqs7_a_t||tdqs7_a_t\  BI  = M_K_CPU0_SA_DQS_DP<7>
  180  VSS77  POWER  = GND
  181  DQ22_A  BI  = M_K_CPU0_SA_DQ<22>
  182  VSS78  POWER  = GND
  183  DQ23_A  BI  = M_K_CPU0_SA_DQ<23>
  184  VSS79  POWER  = GND
  185  DQ26_A  BI  = M_K_CPU0_SA_DQ<26>
  186  VSS80  POWER  = GND
  187  DQ27_A  BI  = M_K_CPU0_SA_DQ<27>
  188  VSS81  POWER  = GND
  189  \dqs8_a_c||tdqs8_a_c\  BI  = M_K_CPU0_SA_DQS_DN<8>
  190  \dqs8_a_t||tdqs8_a_t\  BI  = M_K_CPU0_SA_DQS_DP<8>
  191  VSS82  POWER  = GND
  192  DQ30_A  BI  = M_K_CPU0_SA_DQ<30>
  193  VSS83  POWER  = GND
  194  DQ31_A  BI  = M_K_CPU0_SA_DQ<31>
  195  VSS84  POWER  = GND
  196  CB2_A  BI  = M_K_CPU0_SA_CB<2>
  197  VSS85  POWER  = GND
  198  CB3_A  BI  = M_K_CPU0_SA_CB<3>
  199  VSS86  POWER  = GND
  200  \dqs9_a_c||tdqs9_a_c\  BI  = M_K_CPU0_SA_DQS_DN<9>
  201  \dqs9_a_t||tdqs9_a_t\  BI  = M_K_CPU0_SA_DQS_DP<9>
  202  VSS87  POWER  = GND
  203  CB6_A  BI  = M_K_CPU0_SA_CB<6>
  204  VSS88  POWER  = GND
  205  CB7_A  BI  = M_K_CPU0_SA_CB<7>
  206  VSS89  POWER  = GND
  207  RESET_N  IN  = M_K_CPU0_RESET_N
  208  VSS90  POWER  = GND
  209  CS1_A_N  IN  = M_K_CPU0_SA_CS_N<1>
  210  VSS91  POWER  = GND
  211  CA1_A  IN  = M_K_CPU0_SA_CA<1>
  212  VSS92  POWER  = GND
  213  CA3_A  IN  = M_K_CPU0_SA_CA<3>
  214  VSS93  POWER  = GND
  215  CA5_A  IN  = M_K_CPU0_SA_CA<5>
  216  VSS94  POWER  = GND
  217  CK_T  IN  = M_K_CPU0_CLK_DP<0>
  218  CK_C  IN  = M_K_CPU0_CLK_DN<0>
  219  VSS95  POWER  = GND
  220  RFU4  TRI  = NC
  221  CA1_B  IN  = M_K_CPU0_SB_CA<1>
  222  VSS96  POWER  = GND
  223  CA3_B  IN  = M_K_CPU0_SB_CA<3>
  224  VSS97  POWER  = GND
  225  CA5_B  IN  = M_K_CPU0_SB_CA<5>
  226  VSS98  POWER  = GND
  227  PAR_B  IN  = M_K_CPU0_SB_PAR
  228  VSS99  POWER  = GND
  229  CS1_B_N  IN  = M_K_CPU0_SB_CS_N<1>
  230  VSS100  POWER  = GND
  231  RFU5  TRI  = NC
  232  RFU6  TRI  = NC
  233  VSS101  POWER  = GND
  234  CB6_B  BI  = M_K_CPU0_SB_CB<6>
  235  VSS102  POWER  = GND
  236  CB7_B  BI  = M_K_CPU0_SB_CB<7>
  237  VSS103  POWER  = GND
  238  DQS4_B_C  BI  = M_K_CPU0_SB_DQS_DN<4>
  239  DQS4_B_T  BI  = M_K_CPU0_SB_DQS_DP<4>
  240  VSS104  POWER  = GND
  241  CB2_B  BI  = M_K_CPU0_SB_CB<2>
  242  VSS105  POWER  = GND
  243  CB3_B  BI  = M_K_CPU0_SB_CB<3>
  244  VSS106  POWER  = GND
  245  DQ2_B  BI  = M_K_CPU0_SB_DQ<2>
  246  VSS107  POWER  = GND
  247  DQ3_B  BI  = M_K_CPU0_SB_DQ<3>
  248  VSS108  POWER  = GND
  249  \dqs5_b_c||tdqs5_b_c\  BI  = M_K_CPU0_SB_DQS_DN<5>
  250  \dqs5_b_t||tdqs5_b_t\  BI  = M_K_CPU0_SB_DQS_DP<5>
  251  VSS109  POWER  = GND
  252  DQ6_B  BI  = M_K_CPU0_SB_DQ<6>
  253  VSS110  POWER  = GND
  254  DQ7_B  BI  = M_K_CPU0_SB_DQ<7>
  255  VSS111  POWER  = GND
  256  DQ10_B  BI  = M_K_CPU0_SB_DQ<10>
  257  VSS112  POWER  = GND
  258  DQ11_B  BI  = M_K_CPU0_SB_DQ<11>
  259  VSS113  POWER  = GND
  260  \dqs6_b_c||tdqs6_b_c\  BI  = M_K_CPU0_SB_DQS_DN<6>
  261  \dqs6_b_t||tdqs6_b_t\  BI  = M_K_CPU0_SB_DQS_DP<6>
  262  VSS114  POWER  = GND
  263  DQ14_B  BI  = M_K_CPU0_SB_DQ<14>
  264  VSS115  POWER  = GND
  265  DQ15_B  BI  = M_K_CPU0_SB_DQ<15>
  266  VSS116  POWER  = GND
  267  DQ18_B  BI  = M_K_CPU0_SB_DQ<18>
  268  VSS117  POWER  = GND
  269  DQ19_B  BI  = M_K_CPU0_SB_DQ<19>
  270  VSS118  POWER  = GND
  271  \dqs7_b_c||tdqs7_b_c\  BI  = M_K_CPU0_SB_DQS_DN<7>
  272  \dqs7_b_t||tdqs7_b_t\  BI  = M_K_CPU0_SB_DQS_DP<7>
  273  VSS119  POWER  = GND
  274  DQ22_B  BI  = M_K_CPU0_SB_DQ<22>
  275  VSS120  POWER  = GND
  276  DQ23_B  BI  = M_K_CPU0_SB_DQ<23>
  277  VSS121  POWER  = GND
  278  DQ26_B  BI  = M_K_CPU0_SB_DQ<26>
  279  VSS122  POWER  = GND
  280  DQ27_B  BI  = M_K_CPU0_SB_DQ<27>
  281  VSS123  POWER  = GND
  282  \dqs8_b_c||tdqs8_b_c\  BI  = M_K_CPU0_SB_DQS_DN<8>
  283  \dqs8_b_t||tdqs8_b_t\  BI  = M_K_CPU0_SB_DQS_DP<8>
  284  VSS124  POWER  = GND
  285  DQ30_B  BI  = M_K_CPU0_SB_DQ<30>
  286  VSS125  POWER  = GND
  287  DQ31_B  BI  = M_K_CPU0_SB_DQ<31>
  288  VSS126  POWER  = GND
  G1  G1  POWER  = GND
  G2  G2  POWER  = GND
  G3  G3  POWER  = GND
